M48
INCH,TZ
T01C.012
T02C.016
T03C.029
T04C.086
T05C.093
T06C.199
;EXTENTS: -102.656 -105.763 111.644 104.637 
;LEADER: 12 
;HEADER: 
;CODE  : ASCII 
;FILE  : 13919-sa.rou for board 13919-sa.brd
%
G90
F1
M16
G40
M30
